# S9S_MB_2U (Grand Teton) — schematic netlist excerpt (pin names and nets, part order shuffled) for the footprints in the layout excerpt that follows; sources: Cadence DE-HDL packaged netlist, KiCad conversion of 03242023_DA0F0TMBIJ0_F0T_Motherboard_J_brd_V01_OCP.brd

R1393  Q_RES  240 1% EMPTY  pkg 0402LF  page 120 : A = GND ; B = FM_S3M_CPU1_LVC1_GPIO_2
R4111  Q_RES  10K 1% CHIP  pkg 0402LF  page 184 : A = PD_PCH_GPP_E_13 ; B = GND
C366  Q_CAP  47UF 4V 20% X6S  pkg C0805  page 76 : A = PVCCIN_CPU0 ; B = GND

(kicad_pcb
	(version 20260206)
	(generator "pcbnew")
	(generator_version "10.0")
	(general
		(thickness 1.6)
		(legacy_teardrops no)
	)
	(paper "A4")
	(title_block
		(title "03242023_DA0F0TMBIJ0_F0T_Motherboard_J_brd_V01_OCP.brd")
		(comment 1 "Grand Teton / footprints 4506-4508 of 6105")
	)
	(layers
		(0 "F.Cu" signal "TOP")
		(4 "In1.Cu" signal "GND")
		(6 "In2.Cu" signal "IN1")
		(8 "In3.Cu" signal "GND1")
		(10 "In4.Cu" signal "IN2")
		(12 "In5.Cu" signal "GND2")
		(14 "In6.Cu" signal "IN3")
		(16 "In7.Cu" signal "GND3")
		(18 "In8.Cu" signal "VCC")
		(20 "In9.Cu" signal "VCC1")
		(22 "In10.Cu" signal "GND4")
		(24 "In11.Cu" signal "IN4")
		(26 "In12.Cu" signal "GND5")
		(28 "In13.Cu" signal "IN5")
		(30 "In14.Cu" signal "GND6")
		(32 "In15.Cu" signal "IN6")
		(34 "In16.Cu" signal "GND7")
		(2 "B.Cu" signal "BOTTOM")
		(9 "F.Adhes" user "F.Adhesive")
		(11 "B.Adhes" user "B.Adhesive")
		(13 "F.Paste" user "Package Geometry/Pastemask Top")
		(15 "B.Paste" user "Package Geometry/Pastemask Bottom")
		(5 "F.SilkS" user "Ref Des/Silkscreen Top")
		(7 "B.SilkS" user "Ref Des/Silkscreen Bottom")
		(1 "F.Mask" user "Board Geometry/Soldermask Top")
		(3 "B.Mask" user "Board Geometry/Soldermask Bottom")
		(17 "Dwgs.User" user "User.Drawings")
		(19 "Cmts.User" user "User.Comments")
		(21 "Eco1.User" user "User.Eco1")
		(23 "Eco2.User" user "User.Eco2")
		(25 "Edge.Cuts" user "Board Geometry/Outline")
		(27 "Margin" user)
		(31 "F.CrtYd" user "Package Geometry/Place Bound Top")
		(29 "B.CrtYd" user "Package Geometry/Place Bound Bottom")
		(35 "F.Fab" user "Ref Des/Assembly Top")
		(33 "B.Fab" user "Ref Des/Assembly Bottom")
	)
	(footprint ""
		(layer "B.Cu")
		(at 50.698908 -193.25971 -90)
		(property "Reference" "R1393"
			(at 0 0 90)
			(layer "B.SilkS")
			(hide yes)
			(effects
				(font
					(size 1.27 1.27)
				)
				(justify mirror)
			)
		)
		(property "Value" ""
			(at 0 0 90)
			(layer "B.Fab")
			(effects
				(font
					(size 1.27 1.27)
				)
				(justify mirror)
			)
		)
		(duplicate_pad_numbers_are_jumpers no)
		(fp_line
			(start -0.7874 0.4064)
			(end 0.7874 0.4064)
			(stroke
				(width 0.1524)
				(type default)
			)
			(layer "B.SilkS")
		)
		(fp_line
			(start 0.7874 0.4064)
			(end 0.7874 -0.4064)
			(stroke
				(width 0.1524)
				(type default)
			)
			(layer "B.SilkS")
		)
		(fp_line
			(start -0.7874 -0.4064)
			(end -0.7874 0.4064)
			(stroke
				(width 0.1524)
				(type default)
			)
			(layer "B.SilkS")
		)
		(fp_line
			(start 0.7874 -0.4064)
			(end -0.7874 -0.4064)
			(stroke
				(width 0.1524)
				(type default)
			)
			(layer "B.SilkS")
		)
		(fp_line
			(start -0.67945 0.3048)
			(end -0.120396 0.3048)
			(stroke
				(width 0.1)
				(type default)
			)
			(layer "B.Fab")
		)
		(fp_line
			(start -0.120396 0.3048)
			(end -0.120396 0.2794)
			(stroke
				(width 0.1)
				(type default)
			)
			(layer "B.Fab")
		)
		(fp_line
			(start 0.12065 0.3048)
			(end 0.67945 0.3048)
			(stroke
				(width 0.1)
				(type default)
			)
			(layer "B.Fab")
		)
		(fp_line
			(start 0.67945 0.3048)
			(end 0.67945 -0.305054)
			(stroke
				(width 0.1)
				(type default)
			)
			(layer "B.Fab")
		)
		(fp_line
			(start -0.120396 0.2794)
			(end 0.12065 0.2794)
			(stroke
				(width 0.1)
				(type default)
			)
			(layer "B.Fab")
		)
		(fp_line
			(start 0.12065 0.2794)
			(end 0.12065 0.3048)
			(stroke
				(width 0.1)
				(type default)
			)
			(layer "B.Fab")
		)
		(fp_line
			(start -0.12065 -0.2794)
			(end -0.12065 -0.3048)
			(stroke
				(width 0.1)
				(type default)
			)
			(layer "B.Fab")
		)
		(fp_line
			(start 0.12065 -0.2794)
			(end -0.12065 -0.2794)
			(stroke
				(width 0.1)
				(type default)
			)
			(layer "B.Fab")
		)
		(fp_line
			(start -0.67945 -0.3048)
			(end -0.67945 0.3048)
			(stroke
				(width 0.1)
				(type default)
			)
			(layer "B.Fab")
		)
		(fp_line
			(start -0.12065 -0.3048)
			(end -0.67945 -0.3048)
			(stroke
				(width 0.1)
				(type default)
			)
			(layer "B.Fab")
		)
		(fp_line
			(start 0.12065 -0.305054)
			(end 0.12065 -0.2794)
			(stroke
				(width 0.1)
				(type default)
			)
			(layer "B.Fab")
		)
		(fp_line
			(start 0.67945 -0.305054)
			(end 0.12065 -0.305054)
			(stroke
				(width 0.1)
				(type default)
			)
			(layer "B.Fab")
		)
		(pad "1" smd circle
			(at 0.40005 0 90)
			(size 0 0)
			(layers "B.Cu" "B.Mask" "B.Paste")
			(net "GND")
		)
		(pad "2" smd circle
			(at -0.40005 0 90)
			(size 0 0)
			(layers "B.Cu" "B.Mask" "B.Paste")
			(net "FM_S3M_CPU1_LVC1_GPIO_2")
		)
	)
	(footprint ""
		(layer "B.Cu")
		(at 369.49888 -41.112948 180)
		(property "Reference" "R4111"
			(at 0 0 0)
			(layer "B.SilkS")
			(hide yes)
			(effects
				(font
					(size 1.27 1.27)
				)
				(justify mirror)
			)
		)
		(property "Value" ""
			(at 0 0 0)
			(layer "B.Fab")
			(effects
				(font
					(size 1.27 1.27)
				)
				(justify mirror)
			)
		)
		(duplicate_pad_numbers_are_jumpers no)
		(fp_line
			(start 0.7874 0.4064)
			(end 0.7874 -0.4064)
			(stroke
				(width 0.1524)
				(type default)
			)
			(layer "B.SilkS")
		)
		(fp_line
			(start 0.7874 -0.4064)
			(end -0.7874 -0.4064)
			(stroke
				(width 0.1524)
				(type default)
			)
			(layer "B.SilkS")
		)
		(fp_line
			(start -0.7874 0.4064)
			(end 0.7874 0.4064)
			(stroke
				(width 0.1524)
				(type default)
			)
			(layer "B.SilkS")
		)
		(fp_line
			(start -0.7874 -0.4064)
			(end -0.7874 0.4064)
			(stroke
				(width 0.1524)
				(type default)
			)
			(layer "B.SilkS")
		)
		(fp_line
			(start 0.67945 0.3048)
			(end 0.67945 -0.305054)
			(stroke
				(width 0.1)
				(type default)
			)
			(layer "B.Fab")
		)
		(fp_line
			(start 0.67945 -0.305054)
			(end 0.12065 -0.305054)
			(stroke
				(width 0.1)
				(type default)
			)
			(layer "B.Fab")
		)
		(fp_line
			(start 0.12065 0.3048)
			(end 0.67945 0.3048)
			(stroke
				(width 0.1)
				(type default)
			)
			(layer "B.Fab")
		)
		(fp_line
			(start 0.12065 0.2794)
			(end 0.12065 0.3048)
			(stroke
				(width 0.1)
				(type default)
			)
			(layer "B.Fab")
		)
		(fp_line
			(start 0.12065 -0.2794)
			(end -0.12065 -0.2794)
			(stroke
				(width 0.1)
				(type default)
			)
			(layer "B.Fab")
		)
		(fp_line
			(start 0.12065 -0.305054)
			(end 0.12065 -0.2794)
			(stroke
				(width 0.1)
				(type default)
			)
			(layer "B.Fab")
		)
		(fp_line
			(start -0.120396 0.3048)
			(end -0.120396 0.2794)
			(stroke
				(width 0.1)
				(type default)
			)
			(layer "B.Fab")
		)
		(fp_line
			(start -0.120396 0.2794)
			(end 0.12065 0.2794)
			(stroke
				(width 0.1)
				(type default)
			)
			(layer "B.Fab")
		)
		(fp_line
			(start -0.12065 -0.2794)
			(end -0.12065 -0.3048)
			(stroke
				(width 0.1)
				(type default)
			)
			(layer "B.Fab")
		)
		(fp_line
			(start -0.12065 -0.3048)
			(end -0.67945 -0.3048)
			(stroke
				(width 0.1)
				(type default)
			)
			(layer "B.Fab")
		)
		(fp_line
			(start -0.67945 0.3048)
			(end -0.120396 0.3048)
			(stroke
				(width 0.1)
				(type default)
			)
			(layer "B.Fab")
		)
		(fp_line
			(start -0.67945 -0.3048)
			(end -0.67945 0.3048)
			(stroke
				(width 0.1)
				(type default)
			)
			(layer "B.Fab")
		)
		(pad "1" smd circle
			(at 0.40005 0)
			(size 0 0)
			(layers "B.Cu" "B.Mask" "B.Paste")
			(net "PD_PCH_GPP_E_13")
		)
		(pad "2" smd circle
			(at -0.40005 0)
			(size 0 0)
			(layers "B.Cu" "B.Mask" "B.Paste")
			(net "GND")
		)
	)
	(footprint ""
		(layer "B.Cu")
		(at 350.435418 -294.009826 180)
		(property "Reference" "C366"
			(at 0 0 0)
			(layer "B.SilkS")
			(hide yes)
			(effects
				(font
					(size 1.27 1.27)
				)
				(justify mirror)
			)
		)
		(property "Value" ""
			(at 0 0 0)
			(layer "B.Fab")
			(effects
				(font
					(size 1.27 1.27)
				)
				(justify mirror)
			)
		)
		(duplicate_pad_numbers_are_jumpers no)
		(fp_line
			(start 1.524 0.762)
			(end 1.524 -0.762)
			(stroke
				(width 0.1524)
				(type default)
			)
			(layer "B.SilkS")
		)
		(fp_line
			(start 1.524 -0.762)
			(end -1.524 -0.762)
			(stroke
				(width 0.1524)
				(type default)
			)
			(layer "B.SilkS")
		)
		(fp_line
			(start -1.524 0.762)
			(end 1.524 0.762)
			(stroke
				(width 0.1524)
				(type default)
			)
			(layer "B.SilkS")
		)
		(fp_line
			(start -1.524 -0.762)
			(end -1.524 0.762)
			(stroke
				(width 0.1524)
				(type default)
			)
			(layer "B.SilkS")
		)
		(fp_line
			(start 1.1049 0.724916)
			(end -1.1049 0.724916)
			(stroke
				(width 0.1)
				(type default)
			)
			(layer "B.Fab")
		)
		(fp_line
			(start 1.1049 -0.724916)
			(end 1.1049 0.724916)
			(stroke
				(width 0.1)
				(type default)
			)
			(layer "B.Fab")
		)
		(fp_line
			(start -1.1049 0.724916)
			(end -1.1049 -0.724916)
			(stroke
				(width 0.1)
				(type default)
			)
			(layer "B.Fab")
		)
		(fp_line
			(start -1.1049 -0.724916)
			(end 1.1049 -0.724916)
			(stroke
				(width 0.1)
				(type default)
			)
			(layer "B.Fab")
		)
		(pad "1" smd rect
			(at 0.889 0 180)
			(size 1.016 1.27)
			(layers "B.Cu" "B.Mask" "B.Paste")
			(net "PVCCIN_CPU0")
		)
		(pad "2" smd rect
			(at -0.889 0 180)
			(size 1.016 1.27)
			(layers "B.Cu" "B.Mask" "B.Paste")
			(net "GND")
		)
	)
)
